# S9S_MB_2U (Grand Teton) — schematic netlist excerpt (pin names and nets, part order shuffled) for the footprints in the layout excerpt that follows; sources: Cadence DE-HDL packaged netlist, KiCad conversion of 03242023_DA0F0TMBIJ0_F0T_Motherboard_J_brd_V01_OCP.brd

R3879  Q_RES  49.9 1% CHIP  pkg 0402LF  page 86 : A = I3C_SPD_DDRABCD_CPU0_LVC1_SCL_4 ; B = I3C_SPD_DDRABCD_CPU0_LVC1_SCL
PR135  Q_RES  2.2 1% CHIP  pkg 0402LF  page 270 : A = PVCCIN_CPU0_PVCC ; B = PVCCIN_CPU0_VDD7

(kicad_pcb
	(version 20260206)
	(generator "pcbnew")
	(generator_version "10.0")
	(general
		(thickness 1.6)
		(legacy_teardrops no)
	)
	(paper "A4")
	(title_block
		(title "03242023_DA0F0TMBIJ0_F0T_Motherboard_J_brd_V01_OCP.brd")
		(comment 1 "Grand Teton / footprints 4407-4408 of 6105")
	)
	(layers
		(0 "F.Cu" signal "TOP")
		(4 "In1.Cu" signal "GND")
		(6 "In2.Cu" signal "IN1")
		(8 "In3.Cu" signal "GND1")
		(10 "In4.Cu" signal "IN2")
		(12 "In5.Cu" signal "GND2")
		(14 "In6.Cu" signal "IN3")
		(16 "In7.Cu" signal "GND3")
		(18 "In8.Cu" signal "VCC")
		(20 "In9.Cu" signal "VCC1")
		(22 "In10.Cu" signal "GND4")
		(24 "In11.Cu" signal "IN4")
		(26 "In12.Cu" signal "GND5")
		(28 "In13.Cu" signal "IN5")
		(30 "In14.Cu" signal "GND6")
		(32 "In15.Cu" signal "IN6")
		(34 "In16.Cu" signal "GND7")
		(2 "B.Cu" signal "BOTTOM")
		(9 "F.Adhes" user "F.Adhesive")
		(11 "B.Adhes" user "B.Adhesive")
		(13 "F.Paste" user "Package Geometry/Pastemask Top")
		(15 "B.Paste" user "Package Geometry/Pastemask Bottom")
		(5 "F.SilkS" user "Ref Des/Silkscreen Top")
		(7 "B.SilkS" user "Ref Des/Silkscreen Bottom")
		(1 "F.Mask" user "Board Geometry/Soldermask Top")
		(3 "B.Mask" user "Board Geometry/Soldermask Bottom")
		(17 "Dwgs.User" user "User.Drawings")
		(19 "Cmts.User" user "User.Comments")
		(21 "Eco1.User" user "User.Eco1")
		(23 "Eco2.User" user "User.Eco2")
		(25 "Edge.Cuts" user "Board Geometry/Outline")
		(27 "Margin" user)
		(31 "F.CrtYd" user "Package Geometry/Place Bound Top")
		(29 "B.CrtYd" user "Package Geometry/Place Bound Bottom")
		(35 "F.Fab" user "Ref Des/Assembly Top")
		(33 "B.Fab" user "Ref Des/Assembly Bottom")
	)
	(footprint ""
		(layer "B.Cu")
		(at 325.707502 -343.927938 -90)
		(property "Reference" "PR135"
			(at 0 0 90)
			(layer "B.SilkS")
			(hide yes)
			(effects
				(font
					(size 1.27 1.27)
				)
				(justify mirror)
			)
		)
		(property "Value" ""
			(at 0 0 90)
			(layer "B.Fab")
			(effects
				(font
					(size 1.27 1.27)
				)
				(justify mirror)
			)
		)
		(duplicate_pad_numbers_are_jumpers no)
		(fp_line
			(start -0.7874 0.4064)
			(end 0.7874 0.4064)
			(stroke
				(width 0.1524)
				(type default)
			)
			(layer "B.SilkS")
		)
		(fp_line
			(start 0.7874 0.4064)
			(end 0.7874 -0.4064)
			(stroke
				(width 0.1524)
				(type default)
			)
			(layer "B.SilkS")
		)
		(fp_line
			(start -0.7874 -0.4064)
			(end -0.7874 0.4064)
			(stroke
				(width 0.1524)
				(type default)
			)
			(layer "B.SilkS")
		)
		(fp_line
			(start 0.7874 -0.4064)
			(end -0.7874 -0.4064)
			(stroke
				(width 0.1524)
				(type default)
			)
			(layer "B.SilkS")
		)
		(fp_line
			(start -0.67945 0.3048)
			(end -0.120396 0.3048)
			(stroke
				(width 0.1)
				(type default)
			)
			(layer "B.Fab")
		)
		(fp_line
			(start -0.120396 0.3048)
			(end -0.120396 0.2794)
			(stroke
				(width 0.1)
				(type default)
			)
			(layer "B.Fab")
		)
		(fp_line
			(start 0.12065 0.3048)
			(end 0.67945 0.3048)
			(stroke
				(width 0.1)
				(type default)
			)
			(layer "B.Fab")
		)
		(fp_line
			(start 0.67945 0.3048)
			(end 0.67945 -0.305054)
			(stroke
				(width 0.1)
				(type default)
			)
			(layer "B.Fab")
		)
		(fp_line
			(start -0.120396 0.2794)
			(end 0.12065 0.2794)
			(stroke
				(width 0.1)
				(type default)
			)
			(layer "B.Fab")
		)
		(fp_line
			(start 0.12065 0.2794)
			(end 0.12065 0.3048)
			(stroke
				(width 0.1)
				(type default)
			)
			(layer "B.Fab")
		)
		(fp_line
			(start -0.12065 -0.2794)
			(end -0.12065 -0.3048)
			(stroke
				(width 0.1)
				(type default)
			)
			(layer "B.Fab")
		)
		(fp_line
			(start 0.12065 -0.2794)
			(end -0.12065 -0.2794)
			(stroke
				(width 0.1)
				(type default)
			)
			(layer "B.Fab")
		)
		(fp_line
			(start -0.67945 -0.3048)
			(end -0.67945 0.3048)
			(stroke
				(width 0.1)
				(type default)
			)
			(layer "B.Fab")
		)
		(fp_line
			(start -0.12065 -0.3048)
			(end -0.67945 -0.3048)
			(stroke
				(width 0.1)
				(type default)
			)
			(layer "B.Fab")
		)
		(fp_line
			(start 0.12065 -0.305054)
			(end 0.12065 -0.2794)
			(stroke
				(width 0.1)
				(type default)
			)
			(layer "B.Fab")
		)
		(fp_line
			(start 0.67945 -0.305054)
			(end 0.12065 -0.305054)
			(stroke
				(width 0.1)
				(type default)
			)
			(layer "B.Fab")
		)
		(pad "1" smd circle
			(at 0.40005 0 90)
			(size 0 0)
			(layers "B.Cu" "B.Mask" "B.Paste")
			(net "PVCCIN_CPU0_PVCC")
		)
		(pad "2" smd circle
			(at -0.40005 0 90)
			(size 0 0)
			(layers "B.Cu" "B.Mask" "B.Paste")
			(net "PVCCIN_CPU0_VDD7")
		)
	)
	(footprint ""
		(layer "B.Cu")
		(at 271.180814 -317.824358 180)
		(property "Reference" "R3879"
			(at 0 0 0)
			(layer "B.SilkS")
			(hide yes)
			(effects
				(font
					(size 1.27 1.27)
				)
				(justify mirror)
			)
		)
		(property "Value" ""
			(at 0 0 0)
			(layer "B.Fab")
			(effects
				(font
					(size 1.27 1.27)
				)
				(justify mirror)
			)
		)
		(duplicate_pad_numbers_are_jumpers no)
		(fp_line
			(start 0.7874 0.4064)
			(end 0.7874 -0.4064)
			(stroke
				(width 0.1524)
				(type default)
			)
			(layer "B.SilkS")
		)
		(fp_line
			(start 0.7874 -0.4064)
			(end -0.7874 -0.4064)
			(stroke
				(width 0.1524)
				(type default)
			)
			(layer "B.SilkS")
		)
		(fp_line
			(start -0.7874 0.4064)
			(end 0.7874 0.4064)
			(stroke
				(width 0.1524)
				(type default)
			)
			(layer "B.SilkS")
		)
		(fp_line
			(start -0.7874 -0.4064)
			(end -0.7874 0.4064)
			(stroke
				(width 0.1524)
				(type default)
			)
			(layer "B.SilkS")
		)
		(fp_line
			(start 0.67945 0.3048)
			(end 0.67945 -0.305054)
			(stroke
				(width 0.1)
				(type default)
			)
			(layer "B.Fab")
		)
		(fp_line
			(start 0.67945 -0.305054)
			(end 0.12065 -0.305054)
			(stroke
				(width 0.1)
				(type default)
			)
			(layer "B.Fab")
		)
		(fp_line
			(start 0.12065 0.3048)
			(end 0.67945 0.3048)
			(stroke
				(width 0.1)
				(type default)
			)
			(layer "B.Fab")
		)
		(fp_line
			(start 0.12065 0.2794)
			(end 0.12065 0.3048)
			(stroke
				(width 0.1)
				(type default)
			)
			(layer "B.Fab")
		)
		(fp_line
			(start 0.12065 -0.2794)
			(end -0.12065 -0.2794)
			(stroke
				(width 0.1)
				(type default)
			)
			(layer "B.Fab")
		)
		(fp_line
			(start 0.12065 -0.305054)
			(end 0.12065 -0.2794)
			(stroke
				(width 0.1)
				(type default)
			)
			(layer "B.Fab")
		)
		(fp_line
			(start -0.120396 0.3048)
			(end -0.120396 0.2794)
			(stroke
				(width 0.1)
				(type default)
			)
			(layer "B.Fab")
		)
		(fp_line
			(start -0.120396 0.2794)
			(end 0.12065 0.2794)
			(stroke
				(width 0.1)
				(type default)
			)
			(layer "B.Fab")
		)
		(fp_line
			(start -0.12065 -0.2794)
			(end -0.12065 -0.3048)
			(stroke
				(width 0.1)
				(type default)
			)
			(layer "B.Fab")
		)
		(fp_line
			(start -0.12065 -0.3048)
			(end -0.67945 -0.3048)
			(stroke
				(width 0.1)
				(type default)
			)
			(layer "B.Fab")
		)
		(fp_line
			(start -0.67945 0.3048)
			(end -0.120396 0.3048)
			(stroke
				(width 0.1)
				(type default)
			)
			(layer "B.Fab")
		)
		(fp_line
			(start -0.67945 -0.3048)
			(end -0.67945 0.3048)
			(stroke
				(width 0.1)
				(type default)
			)
			(layer "B.Fab")
		)
		(pad "1" smd circle
			(at 0.40005 0)
			(size 0 0)
			(layers "B.Cu" "B.Mask" "B.Paste")
			(net "I3C_SPD_DDRABCD_CPU0_LVC1_SCL_4")
		)
		(pad "2" smd circle
			(at -0.40005 0)
			(size 0 0)
			(layers "B.Cu" "B.Mask" "B.Paste")
			(net "I3C_SPD_DDRABCD_CPU0_LVC1_SCL")
		)
	)
)
